(kicad_pcb
	(version 20260206)
	(generator "pcbnew")
	(generator_version "10.0")
	(general
		(thickness 1.6)
		(legacy_teardrops no)
	)
	(paper "A4")
	(title_block
		(title "peb — Lightning_PEB_BRD.brd")
		(comment 1 "Lightning (Wiwynn / Facebook NVMe JBOF) / footprints 510-516 of 2563")
	)
	(layers
		(0 "F.Cu" signal "TOP")
		(4 "In1.Cu" signal "L2GND")
		(6 "In2.Cu" signal "L3")
		(8 "In3.Cu" signal "L4VCC")
		(10 "In4.Cu" signal "L5VCC")
		(12 "In5.Cu" signal "L6")
		(14 "In6.Cu" signal "L7GND")
		(2 "B.Cu" signal "BOTTOM")
		(9 "F.Adhes" user "F.Adhesive")
		(11 "B.Adhes" user "B.Adhesive")
		(13 "F.Paste" user "Package Geometry/Pastemask Top")
		(15 "B.Paste" user "Package Geometry/Pastemask Bottom")
		(5 "F.SilkS" user "Ref Des/Silkscreen Top")
		(7 "B.SilkS" user "Ref Des/Silkscreen Bottom")
		(1 "F.Mask" user "Board Geometry/Soldermask Top")
		(3 "B.Mask" user "Board Geometry/Soldermask Bottom")
		(17 "Dwgs.User" user "User.Drawings")
		(19 "Cmts.User" user "User.Comments")
		(21 "Eco1.User" user "User.Eco1")
		(23 "Eco2.User" user "User.Eco2")
		(25 "Edge.Cuts" user "Board Geometry/Outline")
		(27 "Margin" user)
		(31 "F.CrtYd" user "Package Geometry/Place Bound Top")
		(29 "B.CrtYd" user "Package Geometry/Place Bound Bottom")
		(35 "F.Fab" user "Ref Des/Assembly Top")
		(33 "B.Fab" user "Ref Des/Assembly Bottom")
	)
	(footprint ""
		(layer "F.Cu")
		(at 133.864604 -67.249294)
		(property "Reference" "U9"
			(at 0 0 0)
			(layer "F.SilkS")
			(hide yes)
			(effects
				(font
					(size 1.27 1.27)
				)
			)
		)
		(property "Value" "N25Q128A11ESE40F-GP"
			(at 0 -13.1572 0)
			(unlocked yes)
			(layer "F.Fab")
			(hide yes)
			(effects
				(font
					(size 1.016 1.016)
					(thickness 0.1524)
				)
			)
		)
		(property "Device Type" "SOIC8-1H86"
			(at 0 -14.6812 0)
			(unlocked yes)
			(layer "F.Fab")
			(hide yes)
			(effects
				(font
					(size 1.016 1.016)
					(thickness 0.1524)
				)
			)
		)
		(duplicate_pad_numbers_are_jumpers no)
		(fp_line
			(start -3.2258 -2.3876)
			(end -3.2258 4.572)
			(stroke
				(width 0.1524)
				(type default)
			)
			(layer "F.SilkS")
		)
		(fp_line
			(start -3.048 4.572)
			(end -3.048 2.3876)
			(stroke
				(width 0.508)
				(type default)
			)
			(layer "F.SilkS")
		)
		(fp_line
			(start -2.3114 0)
			(end -3.2258 -0.9144)
			(stroke
				(width 0.1524)
				(type default)
			)
			(layer "F.SilkS")
		)
		(fp_line
			(start -2.3114 0)
			(end -3.2258 0.9144)
			(stroke
				(width 0.1524)
				(type default)
			)
			(layer "F.SilkS")
		)
		(fp_line
			(start 2.1336 -2.3876)
			(end -3.2258 -2.3876)
			(stroke
				(width 0.1524)
				(type default)
			)
			(layer "F.SilkS")
		)
		(fp_line
			(start 2.1336 -2.3876)
			(end 2.1336 2.3876)
			(stroke
				(width 0.1524)
				(type default)
			)
			(layer "F.SilkS")
		)
		(fp_line
			(start 2.1336 2.3876)
			(end -3.048 2.3876)
			(stroke
				(width 0.1524)
				(type default)
			)
			(layer "F.SilkS")
		)
		(fp_poly
			(pts
				(xy -2.2352 2.3876) (xy 2.1336 2.3876) (xy 2.1336 -2.3876) (xy -2.2352 -2.3876)
			)
			(stroke
				(width 0)
				(type default)
			)
			(fill yes)
			(layer "F.SilkS")
		)
		(fp_poly
			(pts
				(xy -3.302 4.826) (xy 3.302 4.826) (xy 3.302 -4.826) (xy -3.302 -4.826)
			)
			(stroke
				(width 0)
				(type default)
			)
			(fill no)
			(layer "F.CrtYd")
		)
		(fp_poly
			(pts
				(xy -3.302 -4.826) (xy 3.302 -4.826) (xy 3.302 4.826) (xy -3.302 4.826)
			)
			(stroke
				(width 0)
				(type default)
			)
			(fill no)
			(layer "F.Fab")
		)
		(pad "1" smd rect
			(at -1.905 3.4925)
			(size 0.635 1.651)
			(layers "F.Cu" "F.Mask" "F.Paste")
			(net "SPI_CSB0_0")
		)
		(pad "2" smd rect
			(at -0.635 3.4925)
			(size 0.635 1.651)
			(layers "F.Cu" "F.Mask" "F.Paste")
			(net "SPI_DATA0_1_R")
		)
		(pad "3" smd rect
			(at 0.635 3.4925)
			(size 0.635 1.651)
			(layers "F.Cu" "F.Mask" "F.Paste")
			(net "SPI_DATA0_2_R")
		)
		(pad "4" smd rect
			(at 1.905 3.4925)
			(size 0.635 1.651)
			(layers "F.Cu" "F.Mask" "F.Paste")
			(net "GND")
		)
		(pad "5" smd rect
			(at 1.905 -3.4925)
			(size 0.635 1.651)
			(layers "F.Cu" "F.Mask" "F.Paste")
			(net "SPI_DATA0_0_R")
		)
		(pad "6" smd rect
			(at 0.635 -3.4925)
			(size 0.635 1.651)
			(layers "F.Cu" "F.Mask" "F.Paste")
			(net "SPI_CLK0_R")
		)
		(pad "7" smd rect
			(at -0.635 -3.4925)
			(size 0.635 1.651)
			(layers "F.Cu" "F.Mask" "F.Paste")
			(net "SPI_DATA0_3_R")
		)
		(pad "8" smd rect
			(at -1.905 -3.4925)
			(size 0.635 1.651)
			(layers "F.Cu" "F.Mask" "F.Paste")
			(net "P1V8_STBY")
		)
	)
	(footprint ""
		(layer "F.Cu")
		(at 136.324848 -40.39489 90)
		(property "Reference" "R758"
			(at 0 0 90)
			(layer "F.SilkS")
			(hide yes)
			(effects
				(font
					(size 1.27 1.27)
				)
			)
		)
		(property "Value" "0R2J-2-GP"
			(at 0.064008 -3.993896 90)
			(unlocked yes)
			(layer "F.Fab")
			(hide yes)
			(effects
				(font
					(size 1.016 1.016)
					(thickness 0.1524)
				)
			)
		)
		(property "Device Type" "R402H16"
			(at 0.064008 -5.517896 90)
			(unlocked yes)
			(layer "F.Fab")
			(hide yes)
			(effects
				(font
					(size 1.016 1.016)
					(thickness 0.1524)
				)
			)
		)
		(duplicate_pad_numbers_are_jumpers no)
		(fp_line
			(start 0.508 -0.9398)
			(end -0.508 -0.9398)
			(stroke
				(width 0.1524)
				(type default)
			)
			(layer "F.SilkS")
		)
		(fp_line
			(start -0.508 -0.9398)
			(end -0.508 0.9398)
			(stroke
				(width 0.1524)
				(type default)
			)
			(layer "F.SilkS")
		)
		(fp_rect
			(start -0.508 0.9398)
			(end 0.508 -0.9398)
			(stroke
				(width 0)
				(type default)
			)
			(fill no)
			(layer "F.CrtYd")
		)
		(fp_rect
			(start -0.508 0.9398)
			(end 0.508 -0.9398)
			(stroke
				(width 0)
				(type default)
			)
			(fill no)
			(layer "F.Fab")
		)
		(pad "1" smd custom
			(at 0 -0.4445 90)
			(size 0.1397 0.1397)
			(layers "F.Cu" "F.Mask" "F.Paste")
			(net "DUT_TDO_R")
			(options
				(clearance outline)
				(anchor circle)
			)
			(primitives
				(gr_poly
					(pts
						(arc
							(start -0.1778 -0.2794)
							(mid -0.249642 -0.249642)
							(end -0.2794 -0.1778)
						)
						(arc
							(start -0.2794 0.1778)
							(mid -0.249642 0.249642)
							(end -0.1778 0.2794)
						)
						(arc
							(start 0.1778 0.2794)
							(mid 0.249642 0.249642)
							(end 0.2794 0.1778)
						)
						(arc
							(start 0.2794 -0.1778)
							(mid 0.249642 -0.249642)
							(end 0.1778 -0.2794)
						)
					)
					(width 0)
					(fill yes)
				)
			)
		)
		(pad "2" smd custom
			(at 0 0.4445 90)
			(size 0.1397 0.1397)
			(layers "F.Cu" "F.Mask" "F.Paste")
			(net "DUT_TDO")
			(options
				(clearance outline)
				(anchor circle)
			)
			(primitives
				(gr_poly
					(pts
						(arc
							(start -0.1778 -0.2794)
							(mid -0.249642 -0.249642)
							(end -0.2794 -0.1778)
						)
						(arc
							(start -0.2794 0.1778)
							(mid -0.249642 0.249642)
							(end -0.1778 0.2794)
						)
						(arc
							(start 0.1778 0.2794)
							(mid 0.249642 0.249642)
							(end 0.2794 0.1778)
						)
						(arc
							(start 0.2794 -0.1778)
							(mid 0.249642 -0.249642)
							(end 0.1778 -0.2794)
						)
					)
					(width 0)
					(fill yes)
				)
			)
		)
	)
	(footprint ""
		(layer "F.Cu")
		(at 17.7292 -194.5386 180)
		(property "Reference" "C7316"
			(at 0 0 180)
			(layer "F.SilkS")
			(hide yes)
			(effects
				(font
					(size 1.27 1.27)
				)
			)
		)
		(property "Value" "SCD1U25V3JX-GP"
			(at 0 -2.8194 180)
			(unlocked yes)
			(layer "F.Fab")
			(hide yes)
			(effects
				(font
					(size 1.016 1.016)
					(thickness 0.1524)
				)
			)
		)
		(property "Device Type" "C603H36"
			(at 0 -4.3434 180)
			(unlocked yes)
			(layer "F.Fab")
			(hide yes)
			(effects
				(font
					(size 1.016 1.016)
					(thickness 0.1524)
				)
			)
		)
		(duplicate_pad_numbers_are_jumpers no)
		(fp_line
			(start 0.508 0)
			(end -0.508 0)
			(stroke
				(width 0.2032)
				(type default)
			)
			(layer "F.SilkS")
		)
		(fp_rect
			(start -0.5842 1.3335)
			(end 0.5842 -1.3335)
			(stroke
				(width 0)
				(type default)
			)
			(fill no)
			(layer "F.CrtYd")
		)
		(fp_rect
			(start -0.5842 1.3335)
			(end 0.5842 -1.3335)
			(stroke
				(width 0)
				(type default)
			)
			(fill no)
			(layer "F.Fab")
		)
		(pad "1" smd custom
			(at 0 -0.762 180)
			(size 0.2159 0.2159)
			(layers "F.Cu" "F.Mask" "F.Paste")
			(net "MB0_PSET_R")
			(options
				(clearance outline)
				(anchor circle)
			)
			(primitives
				(gr_poly
					(pts
						(arc
							(start -0.3302 -0.4318)
							(mid -0.402042 -0.402042)
							(end -0.4318 -0.3302)
						)
						(arc
							(start -0.4318 0.3302)
							(mid -0.402042 0.402042)
							(end -0.3302 0.4318)
						)
						(arc
							(start 0.3302 0.4318)
							(mid 0.402042 0.402042)
							(end 0.4318 0.3302)
						)
						(arc
							(start 0.4318 -0.3302)
							(mid 0.402042 -0.402042)
							(end 0.3302 -0.4318)
						)
					)
					(width 0)
					(fill yes)
				)
			)
		)
		(pad "2" smd custom
			(at 0 0.762 180)
			(size 0.2159 0.2159)
			(layers "F.Cu" "F.Mask" "F.Paste")
			(net "AGND_CURRENT_MON")
			(options
				(clearance outline)
				(anchor circle)
			)
			(primitives
				(gr_poly
					(pts
						(arc
							(start -0.3302 -0.4318)
							(mid -0.402042 -0.402042)
							(end -0.4318 -0.3302)
						)
						(arc
							(start -0.4318 0.3302)
							(mid -0.402042 0.402042)
							(end -0.3302 0.4318)
						)
						(arc
							(start 0.3302 0.4318)
							(mid 0.402042 0.402042)
							(end 0.4318 0.3302)
						)
						(arc
							(start 0.4318 -0.3302)
							(mid 0.402042 -0.402042)
							(end 0.3302 -0.4318)
						)
					)
					(width 0)
					(fill yes)
				)
			)
		)
	)
	(footprint ""
		(layer "F.Cu")
		(at 335.026 -72.771 90)
		(property "Reference" "PC189"
			(at 0 0 90)
			(layer "F.SilkS")
			(hide yes)
			(effects
				(font
					(size 1.27 1.27)
				)
			)
		)
		(property "Value" "SC1KP50V2KX-1GP"
			(at 1.1811 -2.7051 90)
			(unlocked yes)
			(layer "F.Fab")
			(hide yes)
			(effects
				(font
					(size 1.016 1.016)
					(thickness 0.1524)
				)
			)
		)
		(property "Device Type" "C402H22"
			(at 1.1811 -4.2291 90)
			(unlocked yes)
			(layer "F.Fab")
			(hide yes)
			(effects
				(font
					(size 1.016 1.016)
					(thickness 0.1524)
				)
			)
		)
		(duplicate_pad_numbers_are_jumpers no)
		(fp_rect
			(start -0.4318 0.9525)
			(end 0.4318 -0.9525)
			(stroke
				(width 0)
				(type default)
			)
			(fill no)
			(layer "F.CrtYd")
		)
		(fp_rect
			(start -0.4318 0.9525)
			(end 0.4318 -0.9525)
			(stroke
				(width 0)
				(type default)
			)
			(fill no)
			(layer "F.Fab")
		)
		(pad "1" smd custom
			(at 0 -0.4445 90)
			(size 0.1524 0.1524)
			(layers "F.Cu" "F.Mask" "F.Paste")
			(net "P0V9_E_SW_R")
			(options
				(clearance outline)
				(anchor circle)
			)
			(primitives
				(gr_poly
					(pts
						(arc
							(start 0.3048 -0.2032)
							(mid 0.275042 -0.275042)
							(end 0.2032 -0.3048)
						)
						(arc
							(start -0.2032 -0.3048)
							(mid -0.275042 -0.275042)
							(end -0.3048 -0.2032)
						)
						(arc
							(start -0.3048 0.2032)
							(mid -0.275042 0.275042)
							(end -0.2032 0.3048)
						)
						(arc
							(start 0.2032 0.3048)
							(mid 0.275042 0.275042)
							(end 0.3048 0.2032)
						)
					)
					(width 0)
					(fill yes)
				)
			)
		)
		(pad "2" smd custom
			(at 0 0.4445 90)
			(size 0.1524 0.1524)
			(layers "F.Cu" "F.Mask" "F.Paste")
			(net "P0V9_E_VFB")
			(options
				(clearance outline)
				(anchor circle)
			)
			(primitives
				(gr_poly
					(pts
						(arc
							(start 0.3048 -0.2032)
							(mid 0.275042 -0.275042)
							(end 0.2032 -0.3048)
						)
						(arc
							(start -0.2032 -0.3048)
							(mid -0.275042 -0.275042)
							(end -0.3048 -0.2032)
						)
						(arc
							(start -0.3048 0.2032)
							(mid -0.275042 0.275042)
							(end -0.2032 0.3048)
						)
						(arc
							(start 0.2032 0.3048)
							(mid 0.275042 0.275042)
							(end 0.3048 0.2032)
						)
					)
					(width 0)
					(fill yes)
				)
			)
		)
	)
	(footprint ""
		(layer "F.Cu")
		(at 121.6152 -30.734)
		(property "Reference" "R805"
			(at 0 0 0)
			(layer "F.SilkS")
			(hide yes)
			(effects
				(font
					(size 1.27 1.27)
				)
			)
		)
		(property "Value" "4K7R2F-GP"
			(at 0.064008 -3.993896 0)
			(unlocked yes)
			(layer "F.Fab")
			(hide yes)
			(effects
				(font
					(size 1.016 1.016)
					(thickness 0.1524)
				)
			)
		)
		(property "Device Type" "R402H16"
			(at 0.064008 -5.517896 0)
			(unlocked yes)
			(layer "F.Fab")
			(hide yes)
			(effects
				(font
					(size 1.016 1.016)
					(thickness 0.1524)
				)
			)
		)
		(duplicate_pad_numbers_are_jumpers no)
		(fp_line
			(start -0.508 -0.9398)
			(end -0.508 0.9398)
			(stroke
				(width 0.1524)
				(type default)
			)
			(layer "F.SilkS")
		)
		(fp_line
			(start 0.508 -0.9398)
			(end -0.508 -0.9398)
			(stroke
				(width 0.1524)
				(type default)
			)
			(layer "F.SilkS")
		)
		(fp_rect
			(start -0.508 0.9398)
			(end 0.508 -0.9398)
			(stroke
				(width 0)
				(type default)
			)
			(fill no)
			(layer "F.CrtYd")
		)
		(fp_rect
			(start -0.508 0.9398)
			(end 0.508 -0.9398)
			(stroke
				(width 0)
				(type default)
			)
			(fill no)
			(layer "F.Fab")
		)
		(pad "1" smd custom
			(at 0 -0.4445)
			(size 0.1397 0.1397)
			(layers "F.Cu" "F.Mask" "F.Paste")
			(net "P3V3_STBY")
			(options
				(clearance outline)
				(anchor circle)
			)
			(primitives
				(gr_poly
					(pts
						(arc
							(start -0.1778 -0.2794)
							(mid -0.249642 -0.249642)
							(end -0.2794 -0.1778)
						)
						(arc
							(start -0.2794 0.1778)
							(mid -0.249642 0.249642)
							(end -0.1778 0.2794)
						)
						(arc
							(start 0.1778 0.2794)
							(mid 0.249642 0.249642)
							(end 0.2794 0.1778)
						)
						(arc
							(start 0.2794 -0.1778)
							(mid 0.249642 -0.249642)
							(end 0.1778 -0.2794)
						)
					)
					(width 0)
					(fill yes)
				)
			)
		)
		(pad "2" smd custom
			(at 0 0.4445)
			(size 0.1397 0.1397)
			(layers "F.Cu" "F.Mask" "F.Paste")
			(net "U54_INT_N")
			(options
				(clearance outline)
				(anchor circle)
			)
			(primitives
				(gr_poly
					(pts
						(arc
							(start -0.1778 -0.2794)
							(mid -0.249642 -0.249642)
							(end -0.2794 -0.1778)
						)
						(arc
							(start -0.2794 0.1778)
							(mid -0.249642 0.249642)
							(end -0.1778 0.2794)
						)
						(arc
							(start 0.1778 0.2794)
							(mid 0.249642 0.249642)
							(end 0.2794 0.1778)
						)
						(arc
							(start 0.2794 -0.1778)
							(mid 0.249642 -0.249642)
							(end 0.1778 -0.2794)
						)
					)
					(width 0)
					(fill yes)
				)
			)
		)
	)
	(footprint ""
		(layer "F.Cu")
		(at 217.781124 -190.601092 180)
		(property "Reference" "R552"
			(at 0 0 180)
			(layer "F.SilkS")
			(hide yes)
			(effects
				(font
					(size 1.27 1.27)
				)
			)
		)
		(property "Value" "10KR2F-2-GP"
			(at 0.064008 -3.993896 180)
			(unlocked yes)
			(layer "F.Fab")
			(hide yes)
			(effects
				(font
					(size 1.016 1.016)
					(thickness 0.1524)
				)
			)
		)
		(property "Device Type" "R402H16"
			(at 0.064008 -5.517896 180)
			(unlocked yes)
			(layer "F.Fab")
			(hide yes)
			(effects
				(font
					(size 1.016 1.016)
					(thickness 0.1524)
				)
			)
		)
		(duplicate_pad_numbers_are_jumpers no)
		(fp_line
			(start 0.508 -0.9398)
			(end -0.508 -0.9398)
			(stroke
				(width 0.1524)
				(type default)
			)
			(layer "F.SilkS")
		)
		(fp_line
			(start -0.508 -0.9398)
			(end -0.508 0.9398)
			(stroke
				(width 0.1524)
				(type default)
			)
			(layer "F.SilkS")
		)
		(fp_rect
			(start -0.508 0.9398)
			(end 0.508 -0.9398)
			(stroke
				(width 0)
				(type default)
			)
			(fill no)
			(layer "F.CrtYd")
		)
		(fp_rect
			(start -0.508 0.9398)
			(end 0.508 -0.9398)
			(stroke
				(width 0)
				(type default)
			)
			(fill no)
			(layer "F.Fab")
		)
		(pad "1" smd custom
			(at 0 -0.4445 180)
			(size 0.1397 0.1397)
			(layers "F.Cu" "F.Mask" "F.Paste")
			(net "GND")
			(options
				(clearance outline)
				(anchor circle)
			)
			(primitives
				(gr_poly
					(pts
						(arc
							(start -0.1778 -0.2794)
							(mid -0.249642 -0.249642)
							(end -0.2794 -0.1778)
						)
						(arc
							(start -0.2794 0.1778)
							(mid -0.249642 0.249642)
							(end -0.1778 0.2794)
						)
						(arc
							(start 0.1778 0.2794)
							(mid 0.249642 0.249642)
							(end 0.2794 0.1778)
						)
						(arc
							(start 0.2794 -0.1778)
							(mid 0.249642 -0.249642)
							(end 0.1778 -0.2794)
						)
					)
					(width 0)
					(fill yes)
				)
			)
		)
		(pad "2" smd custom
			(at 0 0.4445 180)
			(size 0.1397 0.1397)
			(layers "F.Cu" "F.Mask" "F.Paste")
			(net "IOEXP3_AD1")
			(options
				(clearance outline)
				(anchor circle)
			)
			(primitives
				(gr_poly
					(pts
						(arc
							(start -0.1778 -0.2794)
							(mid -0.249642 -0.249642)
							(end -0.2794 -0.1778)
						)
						(arc
							(start -0.2794 0.1778)
							(mid -0.249642 0.249642)
							(end -0.1778 0.2794)
						)
						(arc
							(start 0.1778 0.2794)
							(mid 0.249642 0.249642)
							(end 0.2794 0.1778)
						)
						(arc
							(start 0.2794 -0.1778)
							(mid 0.249642 -0.249642)
							(end 0.1778 -0.2794)
						)
					)
					(width 0)
					(fill yes)
				)
			)
		)
	)
	(footprint ""
		(layer "F.Cu")
		(at 273.304 -17.399 90)
		(property "Reference" "SR723"
			(at 0 0 90)
			(layer "F.SilkS")
			(hide yes)
			(effects
				(font
					(size 1.27 1.27)
				)
			)
		)
		(property "Value" "150R2F-1-GP"
			(at 0.064008 -3.993896 90)
			(unlocked yes)
			(layer "F.Fab")
			(hide yes)
			(effects
				(font
					(size 1.016 1.016)
					(thickness 0.1524)
				)
			)
		)
		(property "Device Type" "R402H16"
			(at 0.064008 -5.517896 90)
			(unlocked yes)
			(layer "F.Fab")
			(hide yes)
			(effects
				(font
					(size 1.016 1.016)
					(thickness 0.1524)
				)
			)
		)
		(duplicate_pad_numbers_are_jumpers no)
		(fp_line
			(start 0.508 -0.9398)
			(end -0.508 -0.9398)
			(stroke
				(width 0.1524)
				(type default)
			)
			(layer "F.SilkS")
		)
		(fp_line
			(start -0.508 -0.9398)
			(end -0.508 0.9398)
			(stroke
				(width 0.1524)
				(type default)
			)
			(layer "F.SilkS")
		)
		(fp_rect
			(start -0.508 0.9398)
			(end 0.508 -0.9398)
			(stroke
				(width 0)
				(type default)
			)
			(fill no)
			(layer "F.CrtYd")
		)
		(fp_rect
			(start -0.508 0.9398)
			(end 0.508 -0.9398)
			(stroke
				(width 0)
				(type default)
			)
			(fill no)
			(layer "F.Fab")
		)
		(pad "1" smd custom
			(at 0 -0.4445 90)
			(size 0.1397 0.1397)
			(layers "F.Cu" "F.Mask" "F.Paste")
			(net "P3V3_STBY")
			(options
				(clearance outline)
				(anchor circle)
			)
			(primitives
				(gr_poly
					(pts
						(arc
							(start -0.1778 -0.2794)
							(mid -0.249642 -0.249642)
							(end -0.2794 -0.1778)
						)
						(arc
							(start -0.2794 0.1778)
							(mid -0.249642 0.249642)
							(end -0.1778 0.2794)
						)
						(arc
							(start 0.1778 0.2794)
							(mid 0.249642 0.249642)
							(end 0.2794 0.1778)
						)
						(arc
							(start 0.2794 -0.1778)
							(mid 0.249642 -0.249642)
							(end 0.1778 -0.2794)
						)
					)
					(width 0)
					(fill yes)
				)
			)
		)
		(pad "2" smd custom
			(at 0 0.4445 90)
			(size 0.1397 0.1397)
			(layers "F.Cu" "F.Mask" "F.Paste")
			(net "LED_R_14")
			(options
				(clearance outline)
				(anchor circle)
			)
			(primitives
				(gr_poly
					(pts
						(arc
							(start -0.1778 -0.2794)
							(mid -0.249642 -0.249642)
							(end -0.2794 -0.1778)
						)
						(arc
							(start -0.2794 0.1778)
							(mid -0.249642 0.249642)
							(end -0.1778 0.2794)
						)
						(arc
							(start 0.1778 0.2794)
							(mid 0.249642 0.249642)
							(end 0.2794 0.1778)
						)
						(arc
							(start 0.2794 -0.1778)
							(mid 0.249642 -0.249642)
							(end 0.1778 -0.2794)
						)
					)
					(width 0)
					(fill yes)
				)
			)
		)
	)
)
